(kicad_pcb
	(version 20260206)
	(generator "pcbnew")
	(generator_version "10.0")
	(general
		(thickness 1.6)
		(legacy_teardrops no)
	)
	(paper "A4")
	(title_block
		(title "peb — Lightning_PEB_BRD.brd")
		(comment 1 "Lightning (Wiwynn / Facebook NVMe JBOF) / footprints 2191-2198 of 2563")
	)
	(layers
		(0 "F.Cu" signal "TOP")
		(4 "In1.Cu" signal "L2GND")
		(6 "In2.Cu" signal "L3")
		(8 "In3.Cu" signal "L4VCC")
		(10 "In4.Cu" signal "L5VCC")
		(12 "In5.Cu" signal "L6")
		(14 "In6.Cu" signal "L7GND")
		(2 "B.Cu" signal "BOTTOM")
		(9 "F.Adhes" user "F.Adhesive")
		(11 "B.Adhes" user "B.Adhesive")
		(13 "F.Paste" user "Package Geometry/Pastemask Top")
		(15 "B.Paste" user "Package Geometry/Pastemask Bottom")
		(5 "F.SilkS" user "Ref Des/Silkscreen Top")
		(7 "B.SilkS" user "Ref Des/Silkscreen Bottom")
		(1 "F.Mask" user "Board Geometry/Soldermask Top")
		(3 "B.Mask" user "Board Geometry/Soldermask Bottom")
		(17 "Dwgs.User" user "User.Drawings")
		(19 "Cmts.User" user "User.Comments")
		(21 "Eco1.User" user "User.Eco1")
		(23 "Eco2.User" user "User.Eco2")
		(25 "Edge.Cuts" user "Board Geometry/Outline")
		(27 "Margin" user)
		(31 "F.CrtYd" user "Package Geometry/Place Bound Top")
		(29 "B.CrtYd" user "Package Geometry/Place Bound Bottom")
		(35 "F.Fab" user "Ref Des/Assembly Top")
		(33 "B.Fab" user "Ref Des/Assembly Bottom")
	)
	(footprint ""
		(layer "B.Cu")
		(at 216.5096 -21.7932 180)
		(property "Reference" "R63"
			(at 0 0 0)
			(layer "B.SilkS")
			(hide yes)
			(effects
				(font
					(size 1.27 1.27)
				)
				(justify mirror)
			)
		)
		(property "Value" "10KR2F-2-GP"
			(at -0.064008 -3.993896 180)
			(unlocked yes)
			(layer "B.Fab")
			(hide yes)
			(effects
				(font
					(size 1.016 1.016)
					(thickness 0.1524)
				)
				(justify mirror)
			)
		)
		(property "Device Type" "R402H16"
			(at -0.064008 -5.517896 180)
			(unlocked yes)
			(layer "B.Fab")
			(hide yes)
			(effects
				(font
					(size 1.016 1.016)
					(thickness 0.1524)
				)
				(justify mirror)
			)
		)
		(duplicate_pad_numbers_are_jumpers no)
		(fp_line
			(start 0.508 -0.9398)
			(end 0.508 0.9398)
			(stroke
				(width 0.1524)
				(type default)
			)
			(layer "B.SilkS")
		)
		(fp_line
			(start -0.508 -0.9398)
			(end 0.508 -0.9398)
			(stroke
				(width 0.1524)
				(type default)
			)
			(layer "B.SilkS")
		)
		(fp_rect
			(start 0.508 0.9398)
			(end -0.508 -0.9398)
			(stroke
				(width 0)
				(type default)
			)
			(fill no)
			(layer "B.CrtYd")
		)
		(fp_rect
			(start 0.508 0.9398)
			(end -0.508 -0.9398)
			(stroke
				(width 0)
				(type default)
			)
			(fill no)
			(layer "B.Fab")
		)
		(pad "1" smd custom
			(at 0 -0.4445)
			(size 0.1397 0.1397)
			(layers "B.Cu" "B.Mask" "B.Paste")
			(net "DUT_VDDO")
			(options
				(clearance outline)
				(anchor circle)
			)
			(primitives
				(gr_poly
					(pts
						(arc
							(start -0.1778 0.2794)
							(mid -0.249642 0.249642)
							(end -0.2794 0.1778)
						)
						(arc
							(start -0.2794 -0.1778)
							(mid -0.249642 -0.249642)
							(end -0.1778 -0.2794)
						)
						(arc
							(start 0.1778 -0.2794)
							(mid 0.249642 -0.249642)
							(end 0.2794 -0.1778)
						)
						(arc
							(start 0.2794 0.1778)
							(mid 0.249642 0.249642)
							(end 0.1778 0.2794)
						)
					)
					(width 0)
					(fill yes)
				)
			)
		)
		(pad "2" smd custom
			(at 0 0.4445)
			(size 0.1397 0.1397)
			(layers "B.Cu" "B.Mask" "B.Paste")
			(net "PM8536_RST#")
			(options
				(clearance outline)
				(anchor circle)
			)
			(primitives
				(gr_poly
					(pts
						(arc
							(start -0.1778 0.2794)
							(mid -0.249642 0.249642)
							(end -0.2794 0.1778)
						)
						(arc
							(start -0.2794 -0.1778)
							(mid -0.249642 -0.249642)
							(end -0.1778 -0.2794)
						)
						(arc
							(start 0.1778 -0.2794)
							(mid 0.249642 -0.249642)
							(end 0.2794 -0.1778)
						)
						(arc
							(start 0.2794 0.1778)
							(mid 0.249642 0.249642)
							(end 0.1778 0.2794)
						)
					)
					(width 0)
					(fill yes)
				)
			)
		)
	)
	(footprint ""
		(layer "B.Cu")
		(at 184.785 -71.628 180)
		(property "Reference" "C532"
			(at 0 0 0)
			(layer "B.SilkS")
			(hide yes)
			(effects
				(font
					(size 1.27 1.27)
				)
				(justify mirror)
			)
		)
		(property "Value" "SC4D7U16V5KX-1-GP"
			(at 0.0762 -6.1214 180)
			(unlocked yes)
			(layer "B.Fab")
			(hide yes)
			(effects
				(font
					(size 1.016 1.016)
					(thickness 0.1524)
				)
				(justify mirror)
			)
		)
		(property "Device Type" "C805H56"
			(at 0.0762 -8.1534 180)
			(unlocked yes)
			(layer "B.Fab")
			(hide yes)
			(effects
				(font
					(size 1.016 1.016)
					(thickness 0.1524)
				)
				(justify mirror)
			)
		)
		(duplicate_pad_numbers_are_jumpers no)
		(fp_line
			(start -0.635 0)
			(end 0.635 0)
			(stroke
				(width 0.508)
				(type default)
			)
			(layer "B.SilkS")
		)
		(fp_rect
			(start 0.9652 1.778)
			(end -0.9652 -1.778)
			(stroke
				(width 0)
				(type default)
			)
			(fill no)
			(layer "B.CrtYd")
		)
		(fp_poly
			(pts
				(xy 0.9652 -1.778) (xy -0.9652 -1.778) (xy -0.9652 1.778) (xy 0.9652 1.778)
			)
			(stroke
				(width 0)
				(type default)
			)
			(fill no)
			(layer "B.Fab")
		)
		(pad "1" smd rect
			(at 0 -0.9652)
			(size 1.397 1.143)
			(layers "B.Cu" "B.Mask" "B.Paste")
			(net "DUT_AVD_PCIE")
		)
		(pad "2" smd rect
			(at 0 0.9652)
			(size 1.397 1.143)
			(layers "B.Cu" "B.Mask" "B.Paste")
			(net "GND")
		)
	)
	(footprint ""
		(layer "B.Cu")
		(at 255.505712 -7.01167 90)
		(property "Reference" "R190"
			(at 0 0 90)
			(layer "B.SilkS")
			(hide yes)
			(effects
				(font
					(size 1.27 1.27)
				)
				(justify mirror)
			)
		)
		(property "Value" "0R2J-2-GP"
			(at -0.064008 -3.993896 90)
			(unlocked yes)
			(layer "B.Fab")
			(hide yes)
			(effects
				(font
					(size 1.016 1.016)
					(thickness 0.1524)
				)
				(justify mirror)
			)
		)
		(property "Device Type" "R402H16"
			(at -0.064008 -5.517896 90)
			(unlocked yes)
			(layer "B.Fab")
			(hide yes)
			(effects
				(font
					(size 1.016 1.016)
					(thickness 0.1524)
				)
				(justify mirror)
			)
		)
		(duplicate_pad_numbers_are_jumpers no)
		(fp_line
			(start 0.508 -0.9398)
			(end 0.508 0.9398)
			(stroke
				(width 0.1524)
				(type default)
			)
			(layer "B.SilkS")
		)
		(fp_line
			(start -0.508 -0.9398)
			(end 0.508 -0.9398)
			(stroke
				(width 0.1524)
				(type default)
			)
			(layer "B.SilkS")
		)
		(fp_rect
			(start 0.508 0.9398)
			(end -0.508 -0.9398)
			(stroke
				(width 0)
				(type default)
			)
			(fill no)
			(layer "B.CrtYd")
		)
		(fp_rect
			(start 0.508 0.9398)
			(end -0.508 -0.9398)
			(stroke
				(width 0)
				(type default)
			)
			(fill no)
			(layer "B.Fab")
		)
		(pad "1" smd custom
			(at 0 -0.4445 270)
			(size 0.1397 0.1397)
			(layers "B.Cu" "B.Mask" "B.Paste")
			(net "BMC_I2C5_D_PEB_SCL")
			(options
				(clearance outline)
				(anchor circle)
			)
			(primitives
				(gr_poly
					(pts
						(arc
							(start -0.1778 0.2794)
							(mid -0.249642 0.249642)
							(end -0.2794 0.1778)
						)
						(arc
							(start -0.2794 -0.1778)
							(mid -0.249642 -0.249642)
							(end -0.1778 -0.2794)
						)
						(arc
							(start 0.1778 -0.2794)
							(mid 0.249642 -0.249642)
							(end 0.2794 -0.1778)
						)
						(arc
							(start 0.2794 0.1778)
							(mid 0.249642 0.249642)
							(end 0.1778 0.2794)
						)
					)
					(width 0)
					(fill yes)
				)
			)
		)
		(pad "2" smd custom
			(at 0 0.4445 270)
			(size 0.1397 0.1397)
			(layers "B.Cu" "B.Mask" "B.Paste")
			(net "TEMP_1_SCL")
			(options
				(clearance outline)
				(anchor circle)
			)
			(primitives
				(gr_poly
					(pts
						(arc
							(start -0.1778 0.2794)
							(mid -0.249642 0.249642)
							(end -0.2794 0.1778)
						)
						(arc
							(start -0.2794 -0.1778)
							(mid -0.249642 -0.249642)
							(end -0.1778 -0.2794)
						)
						(arc
							(start 0.1778 -0.2794)
							(mid 0.249642 -0.249642)
							(end 0.2794 -0.1778)
						)
						(arc
							(start 0.2794 0.1778)
							(mid 0.249642 0.249642)
							(end 0.1778 0.2794)
						)
					)
					(width 0)
					(fill yes)
				)
			)
		)
	)
	(footprint ""
		(layer "B.Cu")
		(at 317.5 -55.372)
		(property "Reference" "PC177"
			(at 0 0 0)
			(layer "B.SilkS")
			(hide yes)
			(effects
				(font
					(size 1.27 1.27)
				)
				(justify mirror)
			)
		)
		(property "Value" "SC22U6D3V5MX-5-GP"
			(at 0.0762 -6.1214 0)
			(unlocked yes)
			(layer "B.Fab")
			(hide yes)
			(effects
				(font
					(size 1.016 1.016)
					(thickness 0.1524)
				)
				(justify mirror)
			)
		)
		(property "Device Type" "C805H56"
			(at 0.0762 -8.1534 0)
			(unlocked yes)
			(layer "B.Fab")
			(hide yes)
			(effects
				(font
					(size 1.016 1.016)
					(thickness 0.1524)
				)
				(justify mirror)
			)
		)
		(duplicate_pad_numbers_are_jumpers no)
		(fp_line
			(start -0.635 0)
			(end 0.635 0)
			(stroke
				(width 0.508)
				(type default)
			)
			(layer "B.SilkS")
		)
		(fp_rect
			(start 0.9652 1.778)
			(end -0.9652 -1.778)
			(stroke
				(width 0)
				(type default)
			)
			(fill no)
			(layer "B.CrtYd")
		)
		(fp_poly
			(pts
				(xy 0.9652 -1.778) (xy -0.9652 -1.778) (xy -0.9652 1.778) (xy 0.9652 1.778)
			)
			(stroke
				(width 0)
				(type default)
			)
			(fill no)
			(layer "B.Fab")
		)
		(pad "1" smd rect
			(at 0 -0.9652 180)
			(size 1.397 1.143)
			(layers "B.Cu" "B.Mask" "B.Paste")
			(net "P0V9_E")
		)
		(pad "2" smd rect
			(at 0 0.9652 180)
			(size 1.397 1.143)
			(layers "B.Cu" "B.Mask" "B.Paste")
			(net "GND")
		)
	)
	(footprint ""
		(layer "B.Cu")
		(at 228.6254 -56.989472 90)
		(property "Reference" "C535"
			(at 0 0 90)
			(layer "B.SilkS")
			(hide yes)
			(effects
				(font
					(size 1.27 1.27)
				)
				(justify mirror)
			)
		)
		(property "Value" "SCD1U16V1KX-1-GP"
			(at 2.8321 -1.7399 90)
			(unlocked yes)
			(layer "B.Fab")
			(hide yes)
			(effects
				(font
					(size 1.016 1.016)
					(thickness 0.1524)
				)
				(justify mirror)
			)
		)
		(property "Device Type" "C0201H13"
			(at 2.8321 -3.2639 90)
			(unlocked yes)
			(layer "B.Fab")
			(hide yes)
			(effects
				(font
					(size 1.016 1.016)
					(thickness 0.1524)
				)
				(justify mirror)
			)
		)
		(duplicate_pad_numbers_are_jumpers no)
		(fp_rect
			(start 0.2794 0.6477)
			(end -0.2794 -0.6477)
			(stroke
				(width 0)
				(type default)
			)
			(fill no)
			(layer "B.CrtYd")
		)
		(fp_rect
			(start 0.2794 0.6477)
			(end -0.2794 -0.6477)
			(stroke
				(width 0)
				(type default)
			)
			(fill no)
			(layer "B.Fab")
		)
		(pad "1" smd custom
			(at 0 -0.2794 270)
			(size 0.0762 0.0762)
			(layers "B.Cu" "B.Mask" "B.Paste")
			(net "DUT_AVD_PCIE")
			(options
				(clearance outline)
				(anchor circle)
			)
			(primitives
				(gr_poly
					(pts
						(arc
							(start 0.1524 0.127)
							(mid 0.137521 0.162921)
							(end 0.1016 0.1778)
						)
						(arc
							(start -0.1016 0.1778)
							(mid -0.137521 0.162921)
							(end -0.1524 0.127)
						)
						(arc
							(start -0.1524 -0.127)
							(mid -0.137521 -0.162921)
							(end -0.1016 -0.1778)
						)
						(arc
							(start 0.1016 -0.1778)
							(mid 0.137521 -0.162921)
							(end 0.1524 -0.127)
						)
					)
					(width 0)
					(fill yes)
				)
			)
		)
		(pad "2" smd custom
			(at 0 0.2794 270)
			(size 0.0762 0.0762)
			(layers "B.Cu" "B.Mask" "B.Paste")
			(net "GND")
			(options
				(clearance outline)
				(anchor circle)
			)
			(primitives
				(gr_poly
					(pts
						(arc
							(start 0.1524 0.127)
							(mid 0.137521 0.162921)
							(end 0.1016 0.1778)
						)
						(arc
							(start -0.1016 0.1778)
							(mid -0.137521 0.162921)
							(end -0.1524 0.127)
						)
						(arc
							(start -0.1524 -0.127)
							(mid -0.137521 -0.162921)
							(end -0.1016 -0.1778)
						)
						(arc
							(start 0.1016 -0.1778)
							(mid 0.137521 -0.162921)
							(end 0.1524 -0.127)
						)
					)
					(width 0)
					(fill yes)
				)
			)
		)
	)
	(footprint ""
		(layer "B.Cu")
		(at 310.007 -63.881 180)
		(property "Reference" "PG52"
			(at 0 0 0)
			(layer "B.SilkS")
			(hide yes)
			(effects
				(font
					(size 1.27 1.27)
				)
				(justify mirror)
			)
		)
		(property "Value" "GAP-CLOSE-PWR-3-GP"
			(at -0.0254 -6.5786 180)
			(unlocked yes)
			(layer "B.Fab")
			(hide yes)
			(effects
				(font
					(size 1.016 1.016)
					(thickness 0.1524)
				)
				(justify mirror)
			)
		)
		(property "Device Type" "GAP-CLOSE-PWR-3"
			(at -0.0254 -8.255 180)
			(unlocked yes)
			(layer "B.Fab")
			(hide yes)
			(effects
				(font
					(size 1.016 1.016)
					(thickness 0.1524)
				)
				(justify mirror)
			)
		)
		(duplicate_pad_numbers_are_jumpers no)
		(fp_rect
			(start 0.7112 0.4572)
			(end -0.7112 -0.4572)
			(stroke
				(width 0)
				(type default)
			)
			(fill no)
			(layer "B.CrtYd")
		)
		(fp_poly
			(pts
				(xy 0.7112 -0.4572) (xy -0.7112 -0.4572) (xy -0.7112 0.4572) (xy 0.7112 0.4572)
			)
			(stroke
				(width 0)
				(type default)
			)
			(fill no)
			(layer "B.Fab")
		)
		(pad "1" smd rect
			(at 0.3048 0)
			(size 0.6604 0.762)
			(layers "B.Cu" "B.Mask" "B.Paste")
			(net "DUT_VDD")
		)
		(pad "2" smd rect
			(at -0.3048 0)
			(size 0.6604 0.762)
			(layers "B.Cu" "B.Mask" "B.Paste")
			(net "P0V9_E")
		)
	)
	(footprint ""
		(layer "B.Cu")
		(at 264.033 -13.589)
		(property "Reference" "PC223"
			(at 0 0 0)
			(layer "B.SilkS")
			(hide yes)
			(effects
				(font
					(size 1.27 1.27)
				)
				(justify mirror)
			)
		)
		(property "Value" "SC1U16V3KX-5GP"
			(at 0 -2.8194 0)
			(unlocked yes)
			(layer "B.Fab")
			(hide yes)
			(effects
				(font
					(size 1.016 1.016)
					(thickness 0.1524)
				)
				(justify mirror)
			)
		)
		(property "Device Type" "C603H36"
			(at 0 -4.3434 0)
			(unlocked yes)
			(layer "B.Fab")
			(hide yes)
			(effects
				(font
					(size 1.016 1.016)
					(thickness 0.1524)
				)
				(justify mirror)
			)
		)
		(duplicate_pad_numbers_are_jumpers no)
		(fp_line
			(start -0.508 0)
			(end 0.508 0)
			(stroke
				(width 0.2032)
				(type default)
			)
			(layer "B.SilkS")
		)
		(fp_rect
			(start 0.5842 1.3335)
			(end -0.5842 -1.3335)
			(stroke
				(width 0)
				(type default)
			)
			(fill no)
			(layer "B.CrtYd")
		)
		(fp_rect
			(start 0.5842 1.3335)
			(end -0.5842 -1.3335)
			(stroke
				(width 0)
				(type default)
			)
			(fill no)
			(layer "B.Fab")
		)
		(pad "1" smd custom
			(at 0 -0.762 180)
			(size 0.2159 0.2159)
			(layers "B.Cu" "B.Mask" "B.Paste")
			(net "PWRGD_P1V8_STBY")
			(options
				(clearance outline)
				(anchor circle)
			)
			(primitives
				(gr_poly
					(pts
						(arc
							(start -0.3302 0.4318)
							(mid -0.402042 0.402042)
							(end -0.4318 0.3302)
						)
						(arc
							(start -0.4318 -0.3302)
							(mid -0.402042 -0.402042)
							(end -0.3302 -0.4318)
						)
						(arc
							(start 0.3302 -0.4318)
							(mid 0.402042 -0.402042)
							(end 0.4318 -0.3302)
						)
						(arc
							(start 0.4318 0.3302)
							(mid 0.402042 0.402042)
							(end 0.3302 0.4318)
						)
					)
					(width 0)
					(fill yes)
				)
			)
		)
		(pad "2" smd custom
			(at 0 0.762 180)
			(size 0.2159 0.2159)
			(layers "B.Cu" "B.Mask" "B.Paste")
			(net "GND")
			(options
				(clearance outline)
				(anchor circle)
			)
			(primitives
				(gr_poly
					(pts
						(arc
							(start -0.3302 0.4318)
							(mid -0.402042 0.402042)
							(end -0.4318 0.3302)
						)
						(arc
							(start -0.4318 -0.3302)
							(mid -0.402042 -0.402042)
							(end -0.3302 -0.4318)
						)
						(arc
							(start 0.3302 -0.4318)
							(mid 0.402042 -0.402042)
							(end 0.4318 -0.3302)
						)
						(arc
							(start 0.4318 0.3302)
							(mid 0.402042 0.402042)
							(end 0.3302 0.4318)
						)
					)
					(width 0)
					(fill yes)
				)
			)
		)
	)
	(footprint ""
		(layer "B.Cu")
		(at 229.108 -20.447)
		(property "Reference" "R3702"
			(at 0 0 0)
			(layer "B.SilkS")
			(hide yes)
			(effects
				(font
					(size 1.27 1.27)
				)
				(justify mirror)
			)
		)
		(property "Value" "4K7R2F-GP"
			(at -0.064008 -3.993896 0)
			(unlocked yes)
			(layer "B.Fab")
			(hide yes)
			(effects
				(font
					(size 1.016 1.016)
					(thickness 0.1524)
				)
				(justify mirror)
			)
		)
		(property "Device Type" "R402H16"
			(at -0.064008 -5.517896 0)
			(unlocked yes)
			(layer "B.Fab")
			(hide yes)
			(effects
				(font
					(size 1.016 1.016)
					(thickness 0.1524)
				)
				(justify mirror)
			)
		)
		(duplicate_pad_numbers_are_jumpers no)
		(fp_line
			(start -0.508 -0.9398)
			(end 0.508 -0.9398)
			(stroke
				(width 0.1524)
				(type default)
			)
			(layer "B.SilkS")
		)
		(fp_line
			(start 0.508 -0.9398)
			(end 0.508 0.9398)
			(stroke
				(width 0.1524)
				(type default)
			)
			(layer "B.SilkS")
		)
		(fp_rect
			(start 0.508 0.9398)
			(end -0.508 -0.9398)
			(stroke
				(width 0)
				(type default)
			)
			(fill no)
			(layer "B.CrtYd")
		)
		(fp_rect
			(start 0.508 0.9398)
			(end -0.508 -0.9398)
			(stroke
				(width 0)
				(type default)
			)
			(fill no)
			(layer "B.Fab")
		)
		(pad "1" smd custom
			(at 0 -0.4445 180)
			(size 0.1397 0.1397)
			(layers "B.Cu" "B.Mask" "B.Paste")
			(net "HOST2_RST_N_LS")
			(options
				(clearance outline)
				(anchor circle)
			)
			(primitives
				(gr_poly
					(pts
						(arc
							(start -0.1778 0.2794)
							(mid -0.249642 0.249642)
							(end -0.2794 0.1778)
						)
						(arc
							(start -0.2794 -0.1778)
							(mid -0.249642 -0.249642)
							(end -0.1778 -0.2794)
						)
						(arc
							(start 0.1778 -0.2794)
							(mid 0.249642 -0.249642)
							(end 0.2794 -0.1778)
						)
						(arc
							(start 0.2794 0.1778)
							(mid 0.249642 0.249642)
							(end 0.1778 0.2794)
						)
					)
					(width 0)
					(fill yes)
				)
			)
		)
		(pad "2" smd custom
			(at 0 0.4445 180)
			(size 0.1397 0.1397)
			(layers "B.Cu" "B.Mask" "B.Paste")
			(net "DUT_VDDO")
			(options
				(clearance outline)
				(anchor circle)
			)
			(primitives
				(gr_poly
					(pts
						(arc
							(start -0.1778 0.2794)
							(mid -0.249642 0.249642)
							(end -0.2794 0.1778)
						)
						(arc
							(start -0.2794 -0.1778)
							(mid -0.249642 -0.249642)
							(end -0.1778 -0.2794)
						)
						(arc
							(start 0.1778 -0.2794)
							(mid 0.249642 -0.249642)
							(end 0.2794 -0.1778)
						)
						(arc
							(start 0.2794 0.1778)
							(mid 0.249642 0.249642)
							(end 0.1778 0.2794)
						)
					)
					(width 0)
					(fill yes)
				)
			)
		)
	)
)
